(kicad_pcb
	(version 20260206)
	(generator "pcbnew")
	(generator_version "10.0")
	(general
		(thickness 1.6)
		(legacy_teardrops no)
	)
	(paper "A4")
	(title_block
		(title "v1-chassis-manager — T6M_CM_d_v01_1031_1645.brd")
		(comment 1 "Open CloudServer (Microsoft) / footprints 405-414 of 2512")
	)
	(layers
		(0 "F.Cu" signal "TOP")
		(4 "In1.Cu" signal "GND1")
		(6 "In2.Cu" signal "IN1")
		(8 "In3.Cu" signal "VCC1")
		(10 "In4.Cu" signal "VCC2")
		(12 "In5.Cu" signal "GND2")
		(14 "In6.Cu" signal "IN2")
		(16 "In7.Cu" signal "IN3")
		(18 "In8.Cu" signal "GND3")
		(2 "B.Cu" signal "BOTTOM")
		(9 "F.Adhes" user "F.Adhesive")
		(11 "B.Adhes" user "B.Adhesive")
		(13 "F.Paste" user "Package Geometry/Pastemask Top")
		(15 "B.Paste" user "Package Geometry/Pastemask Bottom")
		(5 "F.SilkS" user "Ref Des/Silkscreen Top")
		(7 "B.SilkS" user "Ref Des/Silkscreen Bottom")
		(1 "F.Mask" user "Board Geometry/Soldermask Top")
		(3 "B.Mask" user "Board Geometry/Soldermask Bottom")
		(17 "Dwgs.User" user "User.Drawings")
		(19 "Cmts.User" user "User.Comments")
		(21 "Eco1.User" user "User.Eco1")
		(23 "Eco2.User" user "User.Eco2")
		(25 "Edge.Cuts" user "Board Geometry/Outline")
		(27 "Margin" user)
		(31 "F.CrtYd" user "Package Geometry/Place Bound Top")
		(29 "B.CrtYd" user "Package Geometry/Place Bound Bottom")
		(35 "F.Fab" user "Ref Des/Assembly Top")
		(33 "B.Fab" user "Ref Des/Assembly Bottom")
	)
	(footprint ""
		(layer "F.Cu")
		(at 106.066844 -139.786868 180)
		(property "Reference" "PR76"
			(at 1.291844 3.15214 0)
			(unlocked yes)
			(layer "F.SilkS")
			(effects
				(font
					(size 0.635 0.4064)
					(thickness 0.1524)
				)
				(justify left)
			)
		)
		(property "Value" ""
			(at 0 0 180)
			(layer "F.Fab")
			(effects
				(font
					(size 1.27 1.27)
				)
			)
		)
		(duplicate_pad_numbers_are_jumpers no)
		(fp_line
			(start 0.7874 0.4064)
			(end -0.7874 0.4064)
			(stroke
				(width 0.1524)
				(type default)
			)
			(layer "F.SilkS")
		)
		(fp_line
			(start 0.7874 -0.4064)
			(end 0.7874 0.4064)
			(stroke
				(width 0.1524)
				(type default)
			)
			(layer "F.SilkS")
		)
		(fp_line
			(start -0.7874 0.4064)
			(end -0.7874 -0.4064)
			(stroke
				(width 0.1524)
				(type default)
			)
			(layer "F.SilkS")
		)
		(fp_line
			(start -0.7874 -0.4064)
			(end 0.7874 -0.4064)
			(stroke
				(width 0.1524)
				(type default)
			)
			(layer "F.SilkS")
		)
		(fp_poly
			(pts
				(xy -0.508 0.2794) (xy -0.508 0.2286) (xy -0.635 0.2286) (xy -0.635 -0.254) (xy -0.5334 -0.254)
				(xy -0.5334 -0.2794) (xy 0.5334 -0.2794) (xy 0.5334 -0.254) (xy 0.635 -0.254) (xy 0.635 0.254) (xy 0.5334 0.254)
				(xy 0.5334 0.2794)
			)
			(stroke
				(width 0)
				(type default)
			)
			(fill no)
			(layer "F.CrtYd")
		)
		(pad "1" smd rect
			(at 0.40005 0 180)
			(size 0.4572 0.508)
			(layers "F.Cu" "F.Mask" "F.Paste")
			(net "VR_PVCCP_NODE1_VCC")
		)
		(pad "2" smd rect
			(at -0.40005 0 180)
			(size 0.4572 0.508)
			(layers "F.Cu" "F.Mask" "F.Paste")
			(net "VR_PVCCP_NODE1_OCSET")
		)
	)
	(footprint ""
		(layer "F.Cu")
		(at 152.545796 -60.01893)
		(property "Reference" "R503"
			(at -1.094994 -1.79451 0)
			(unlocked yes)
			(layer "F.SilkS")
			(effects
				(font
					(size 0.7874 0.5842)
					(thickness 0.1524)
				)
				(justify left)
			)
		)
		(property "Value" ""
			(at 0 0 0)
			(layer "F.Fab")
			(effects
				(font
					(size 1.27 1.27)
				)
			)
		)
		(duplicate_pad_numbers_are_jumpers no)
		(fp_line
			(start -0.7874 -0.4064)
			(end 0.7874 -0.4064)
			(stroke
				(width 0.1524)
				(type default)
			)
			(layer "F.SilkS")
		)
		(fp_line
			(start -0.7874 0.4064)
			(end -0.7874 -0.4064)
			(stroke
				(width 0.1524)
				(type default)
			)
			(layer "F.SilkS")
		)
		(fp_line
			(start 0.7874 -0.4064)
			(end 0.7874 0.4064)
			(stroke
				(width 0.1524)
				(type default)
			)
			(layer "F.SilkS")
		)
		(fp_line
			(start 0.7874 0.4064)
			(end -0.7874 0.4064)
			(stroke
				(width 0.1524)
				(type default)
			)
			(layer "F.SilkS")
		)
		(fp_poly
			(pts
				(xy -0.508 0.2794) (xy -0.508 0.2286) (xy -0.635 0.2286) (xy -0.635 -0.254) (xy -0.5334 -0.254)
				(xy -0.5334 -0.2794) (xy 0.5334 -0.2794) (xy 0.5334 -0.254) (xy 0.635 -0.254) (xy 0.635 0.254) (xy 0.5334 0.254)
				(xy 0.5334 0.2794)
			)
			(stroke
				(width 0)
				(type default)
			)
			(fill no)
			(layer "F.CrtYd")
		)
		(pad "1" smd rect
			(at 0.40005 0)
			(size 0.4572 0.508)
			(layers "F.Cu" "F.Mask" "F.Paste")
			(net "GND")
		)
		(pad "2" smd rect
			(at -0.40005 0)
			(size 0.4572 0.508)
			(layers "F.Cu" "F.Mask" "F.Paste")
			(net "NODE1_USB_TESTMODE")
		)
	)
	(footprint ""
		(layer "F.Cu")
		(at 32.022288 -123.274582 90)
		(property "Reference" "C827"
			(at -2.647442 1.365758 90)
			(unlocked yes)
			(layer "F.SilkS")
			(effects
				(font
					(size 0.7874 0.5842)
					(thickness 0.1524)
				)
				(justify left)
			)
		)
		(property "Value" ""
			(at 0 0 90)
			(layer "F.Fab")
			(effects
				(font
					(size 1.27 1.27)
				)
			)
		)
		(duplicate_pad_numbers_are_jumpers no)
		(fp_line
			(start 0.7874 -0.4064)
			(end 0.7874 0.4064)
			(stroke
				(width 0.1524)
				(type default)
			)
			(layer "F.SilkS")
		)
		(fp_line
			(start -0.7874 -0.4064)
			(end 0.7874 -0.4064)
			(stroke
				(width 0.1524)
				(type default)
			)
			(layer "F.SilkS")
		)
		(fp_line
			(start 0 0.381)
			(end 0 -0.381)
			(stroke
				(width 0.1524)
				(type default)
			)
			(layer "F.SilkS")
		)
		(fp_line
			(start 0.7874 0.4064)
			(end -0.7874 0.4064)
			(stroke
				(width 0.1524)
				(type default)
			)
			(layer "F.SilkS")
		)
		(fp_line
			(start -0.7874 0.4064)
			(end -0.7874 -0.4064)
			(stroke
				(width 0.1524)
				(type default)
			)
			(layer "F.SilkS")
		)
		(fp_poly
			(pts
				(xy -0.5334 0.254) (xy -0.635 0.254) (xy -0.635 0.2286) (xy -0.635 -0.254) (xy -0.5334 -0.254) (xy -0.5334 -0.2794)
				(xy 0.5334 -0.2794) (xy 0.5334 -0.254) (xy 0.635 -0.254) (xy 0.635 0.254) (xy 0.5334 0.254) (xy 0.5334 0.2794)
				(xy -0.508 0.2794) (xy -0.5334 0.2794)
			)
			(stroke
				(width 0)
				(type default)
			)
			(fill no)
			(layer "F.CrtYd")
		)
		(pad "1" smd rect
			(at 0.40005 0 90)
			(size 0.4572 0.508)
			(layers "F.Cu" "F.Mask" "F.Paste")
			(net "P5V_STB_NODE1")
		)
		(pad "2" smd rect
			(at -0.40005 0 90)
			(size 0.4572 0.508)
			(layers "F.Cu" "F.Mask" "F.Paste")
			(net "GND")
		)
	)
	(footprint ""
		(layer "F.Cu")
		(at 184.7596 -175.4632 180)
		(property "Reference" "R1313"
			(at -9.9568 -17.40027 0)
			(unlocked yes)
			(layer "F.SilkS")
			(effects
				(font
					(size 0.7874 0.5842)
					(thickness 0.1524)
				)
				(justify left)
			)
		)
		(property "Value" ""
			(at 0 0 180)
			(layer "F.Fab")
			(effects
				(font
					(size 1.27 1.27)
				)
			)
		)
		(duplicate_pad_numbers_are_jumpers no)
		(fp_line
			(start 0.7874 0.4064)
			(end -0.7874 0.4064)
			(stroke
				(width 0.1524)
				(type default)
			)
			(layer "F.SilkS")
		)
		(fp_line
			(start 0.7874 -0.4064)
			(end 0.7874 0.4064)
			(stroke
				(width 0.1524)
				(type default)
			)
			(layer "F.SilkS")
		)
		(fp_line
			(start -0.7874 0.4064)
			(end -0.7874 -0.4064)
			(stroke
				(width 0.1524)
				(type default)
			)
			(layer "F.SilkS")
		)
		(fp_line
			(start -0.7874 -0.4064)
			(end 0.7874 -0.4064)
			(stroke
				(width 0.1524)
				(type default)
			)
			(layer "F.SilkS")
		)
		(fp_poly
			(pts
				(xy -0.508 0.2794) (xy -0.508 0.2286) (xy -0.635 0.2286) (xy -0.635 -0.254) (xy -0.5334 -0.254)
				(xy -0.5334 -0.2794) (xy 0.5334 -0.2794) (xy 0.5334 -0.254) (xy 0.635 -0.254) (xy 0.635 0.254) (xy 0.5334 0.254)
				(xy 0.5334 0.2794)
			)
			(stroke
				(width 0)
				(type default)
			)
			(fill no)
			(layer "F.CrtYd")
		)
		(pad "1" smd rect
			(at 0.40005 0 180)
			(size 0.4572 0.508)
			(layers "F.Cu" "F.Mask" "F.Paste")
			(net "POWER_SW2_PWR_CTR_12V")
		)
		(pad "2" smd rect
			(at -0.40005 0 180)
			(size 0.4572 0.508)
			(layers "F.Cu" "F.Mask" "F.Paste")
			(net "POWER_SW2_PWR_CTR_12V_R")
		)
	)
	(footprint ""
		(layer "F.Cu")
		(at 85.518752 -137.008362 90)
		(property "Reference" "R1096"
			(at 2.537714 4.13639 90)
			(unlocked yes)
			(layer "F.SilkS")
			(effects
				(font
					(size 0.7874 0.5842)
					(thickness 0.1524)
				)
				(justify left)
			)
		)
		(property "Value" ""
			(at 0 0 90)
			(layer "F.Fab")
			(effects
				(font
					(size 1.27 1.27)
				)
			)
		)
		(duplicate_pad_numbers_are_jumpers no)
		(fp_line
			(start 0.7874 -0.4064)
			(end 0.7874 0.4064)
			(stroke
				(width 0.1524)
				(type default)
			)
			(layer "F.SilkS")
		)
		(fp_line
			(start -0.7874 -0.4064)
			(end 0.7874 -0.4064)
			(stroke
				(width 0.1524)
				(type default)
			)
			(layer "F.SilkS")
		)
		(fp_line
			(start 0.7874 0.4064)
			(end -0.7874 0.4064)
			(stroke
				(width 0.1524)
				(type default)
			)
			(layer "F.SilkS")
		)
		(fp_line
			(start -0.7874 0.4064)
			(end -0.7874 -0.4064)
			(stroke
				(width 0.1524)
				(type default)
			)
			(layer "F.SilkS")
		)
		(fp_poly
			(pts
				(xy -0.508 0.2794) (xy -0.508 0.2286) (xy -0.635 0.2286) (xy -0.635 -0.254) (xy -0.5334 -0.254)
				(xy -0.5334 -0.2794) (xy 0.5334 -0.2794) (xy 0.5334 -0.254) (xy 0.635 -0.254) (xy 0.635 0.254) (xy 0.5334 0.254)
				(xy 0.5334 0.2794)
			)
			(stroke
				(width 0)
				(type default)
			)
			(fill no)
			(layer "F.CrtYd")
		)
		(pad "1" smd rect
			(at 0.40005 0 90)
			(size 0.4572 0.508)
			(layers "F.Cu" "F.Mask" "F.Paste")
			(net "PWRGD_NODE1_P1V26_BMC_PG")
		)
		(pad "2" smd rect
			(at -0.40005 0 90)
			(size 0.4572 0.508)
			(layers "F.Cu" "F.Mask" "F.Paste")
			(net "P3V3_STB_NODE1")
		)
	)
	(footprint ""
		(layer "F.Cu")
		(at 142.173452 -56.523382 180)
		(property "Reference" "R804"
			(at 1.742948 1.290066 0)
			(unlocked yes)
			(layer "F.SilkS")
			(effects
				(font
					(size 0.7874 0.5842)
					(thickness 0.1524)
				)
				(justify left)
			)
		)
		(property "Value" ""
			(at 0 0 180)
			(layer "F.Fab")
			(effects
				(font
					(size 1.27 1.27)
				)
			)
		)
		(duplicate_pad_numbers_are_jumpers no)
		(fp_line
			(start 1.905 0.8636)
			(end -1.905 0.8636)
			(stroke
				(width 0.1524)
				(type default)
			)
			(layer "F.SilkS")
		)
		(fp_line
			(start 1.905 -0.8636)
			(end 1.905 0.8636)
			(stroke
				(width 0.1524)
				(type default)
			)
			(layer "F.SilkS")
		)
		(fp_line
			(start -1.905 0.8636)
			(end -1.905 -0.8636)
			(stroke
				(width 0.1524)
				(type default)
			)
			(layer "F.SilkS")
		)
		(fp_line
			(start -1.905 -0.8636)
			(end 1.905 -0.8636)
			(stroke
				(width 0.1524)
				(type default)
			)
			(layer "F.SilkS")
		)
		(fp_poly
			(pts
				(xy 1.524 0.6858) (xy 1.524 -0.6858) (xy 1.524 -0.7366) (xy -1.524 -0.7366) (xy -1.524 -0.6858)
				(xy -1.524 0.6858) (xy -1.524 0.7366) (xy 1.524 0.7366)
			)
			(stroke
				(width 0)
				(type default)
			)
			(fill no)
			(layer "F.CrtYd")
		)
		(pad "1" smd rect
			(at 0.94996 0 180)
			(size 1.1176 1.3716)
			(layers "F.Cu" "F.Mask" "F.Paste")
			(net "P1V0_NODE1")
		)
		(pad "2" smd rect
			(at -0.94996 0 180)
			(size 1.1176 1.3716)
			(layers "F.Cu" "F.Mask" "F.Paste")
			(net "P1V0_SATA")
		)
	)
	(footprint ""
		(layer "F.Cu")
		(at 174.646336 -61.50991 180)
		(property "Reference" "U54"
			(at -2.29108 0.04191 90)
			(unlocked yes)
			(layer "F.SilkS")
			(effects
				(font
					(size 0.7874 0.5842)
					(thickness 0.1524)
				)
			)
		)
		(property "Value" ""
			(at 0 0 180)
			(layer "F.Fab")
			(effects
				(font
					(size 1.27 1.27)
				)
			)
		)
		(duplicate_pad_numbers_are_jumpers no)
		(fp_line
			(start 1.549908 2.032)
			(end -1.549908 2.032)
			(stroke
				(width 0.1524)
				(type default)
			)
			(layer "F.SilkS")
		)
		(fp_line
			(start 1.549908 -2.032)
			(end 1.549908 2.032)
			(stroke
				(width 0.1524)
				(type default)
			)
			(layer "F.SilkS")
		)
		(fp_line
			(start -1.549908 2.032)
			(end -1.549908 -2.032)
			(stroke
				(width 0.1524)
				(type default)
			)
			(layer "F.SilkS")
		)
		(fp_line
			(start -1.549908 -2.032)
			(end 1.549908 -2.032)
			(stroke
				(width 0.1524)
				(type default)
			)
			(layer "F.SilkS")
		)
		(fp_poly
			(pts
				(xy -0.94996 2.4765) (xy -1.33096 3.6195) (xy -0.56896 3.6195)
			)
			(stroke
				(width 0)
				(type default)
			)
			(fill yes)
			(layer "F.SilkS")
		)
		(fp_poly
			(pts
				(xy -1.1684 1.905) (xy -1.1684 0.8636) (xy -1.5494 0.8636) (xy -1.5494 -0.8636) (xy -1.1684 -0.8636)
				(xy -1.1684 -1.905) (xy 1.1684 -1.905) (xy 1.1684 -0.8636) (xy 1.5494 -0.8636) (xy 1.5494 0.8636)
				(xy 1.1684 0.8636) (xy 1.1684 1.905)
			)
			(stroke
				(width 0)
				(type default)
			)
			(fill no)
			(layer "F.CrtYd")
		)
		(pad "1" smd rect
			(at -0.94996 1.225042 180)
			(size 0.4064 1.3208)
			(layers "F.Cu" "F.Mask" "F.Paste")
			(net "USB3_L_DN")
		)
		(pad "2" smd rect
			(at 0 1.225042 180)
			(size 0.4064 1.3208)
			(layers "F.Cu" "F.Mask" "F.Paste")
			(net "GND")
		)
		(pad "3" smd rect
			(at 0.94996 1.225042 180)
			(size 0.4064 1.3208)
			(layers "F.Cu" "F.Mask" "F.Paste")
			(net "USB3_L_DP")
		)
		(pad "4" smd rect
			(at 0.94996 -1.225042 180)
			(size 0.4064 1.3208)
			(layers "F.Cu" "F.Mask" "F.Paste")
			(net "USB2_L_DP")
		)
		(pad "5" smd rect
			(at 0 -1.225042 180)
			(size 0.4064 1.3208)
			(layers "F.Cu" "F.Mask" "F.Paste")
			(net "USBPWR_P1")
		)
		(pad "6" smd rect
			(at -0.94996 -1.225042 180)
			(size 0.4064 1.3208)
			(layers "F.Cu" "F.Mask" "F.Paste")
			(net "USB2_L_DN")
		)
	)
	(footprint ""
		(layer "F.Cu")
		(at 168.509442 -156.827474)
		(property "Reference" "R582"
			(at -0.455422 2.314448 0)
			(unlocked yes)
			(layer "F.SilkS")
			(effects
				(font
					(size 0.7874 0.5842)
					(thickness 0.1524)
				)
				(justify left)
			)
		)
		(property "Value" ""
			(at 0 0 0)
			(layer "F.Fab")
			(effects
				(font
					(size 1.27 1.27)
				)
			)
		)
		(duplicate_pad_numbers_are_jumpers no)
		(fp_line
			(start -0.7874 -0.4064)
			(end 0.7874 -0.4064)
			(stroke
				(width 0.1524)
				(type default)
			)
			(layer "F.SilkS")
		)
		(fp_line
			(start -0.7874 0.4064)
			(end -0.7874 -0.4064)
			(stroke
				(width 0.1524)
				(type default)
			)
			(layer "F.SilkS")
		)
		(fp_line
			(start 0.7874 -0.4064)
			(end 0.7874 0.4064)
			(stroke
				(width 0.1524)
				(type default)
			)
			(layer "F.SilkS")
		)
		(fp_line
			(start 0.7874 0.4064)
			(end -0.7874 0.4064)
			(stroke
				(width 0.1524)
				(type default)
			)
			(layer "F.SilkS")
		)
		(fp_poly
			(pts
				(xy -0.508 0.2794) (xy -0.508 0.2286) (xy -0.635 0.2286) (xy -0.635 -0.254) (xy -0.5334 -0.254)
				(xy -0.5334 -0.2794) (xy 0.5334 -0.2794) (xy 0.5334 -0.254) (xy 0.635 -0.254) (xy 0.635 0.254) (xy 0.5334 0.254)
				(xy 0.5334 0.2794)
			)
			(stroke
				(width 0)
				(type default)
			)
			(fill no)
			(layer "F.CrtYd")
		)
		(pad "1" smd rect
			(at 0.40005 0)
			(size 0.4572 0.508)
			(layers "F.Cu" "F.Mask" "F.Paste")
			(net "GND")
		)
		(pad "2" smd rect
			(at -0.40005 0)
			(size 0.4572 0.508)
			(layers "F.Cu" "F.Mask" "F.Paste")
			(net "LAN2_DIS_REG10")
		)
	)
	(footprint ""
		(layer "F.Cu")
		(at 144.916652 -144.20215)
		(property "Reference" "R276"
			(at -0.704088 18.585688 0)
			(unlocked yes)
			(layer "F.SilkS")
			(effects
				(font
					(size 0.7874 0.5842)
					(thickness 0.1524)
				)
				(justify left)
			)
		)
		(property "Value" ""
			(at 0 0 0)
			(layer "F.Fab")
			(effects
				(font
					(size 1.27 1.27)
				)
			)
		)
		(duplicate_pad_numbers_are_jumpers no)
		(fp_line
			(start -0.7874 -0.4064)
			(end 0.7874 -0.4064)
			(stroke
				(width 0.1524)
				(type default)
			)
			(layer "F.SilkS")
		)
		(fp_line
			(start -0.7874 0.4064)
			(end -0.7874 -0.4064)
			(stroke
				(width 0.1524)
				(type default)
			)
			(layer "F.SilkS")
		)
		(fp_line
			(start 0.7874 -0.4064)
			(end 0.7874 0.4064)
			(stroke
				(width 0.1524)
				(type default)
			)
			(layer "F.SilkS")
		)
		(fp_line
			(start 0.7874 0.4064)
			(end -0.7874 0.4064)
			(stroke
				(width 0.1524)
				(type default)
			)
			(layer "F.SilkS")
		)
		(fp_poly
			(pts
				(xy -0.508 0.2794) (xy -0.508 0.2286) (xy -0.635 0.2286) (xy -0.635 -0.254) (xy -0.5334 -0.254)
				(xy -0.5334 -0.2794) (xy 0.5334 -0.2794) (xy 0.5334 -0.254) (xy 0.635 -0.254) (xy 0.635 0.254) (xy 0.5334 0.254)
				(xy 0.5334 0.2794)
			)
			(stroke
				(width 0)
				(type default)
			)
			(fill no)
			(layer "F.CrtYd")
		)
		(pad "1" smd rect
			(at 0.40005 0)
			(size 0.4572 0.508)
			(layers "F.Cu" "F.Mask" "F.Paste")
			(net "GND")
		)
		(pad "2" smd rect
			(at -0.40005 0)
			(size 0.4572 0.508)
			(layers "F.Cu" "F.Mask" "F.Paste")
			(net "PCIE_SW_PWR_SAV")
		)
	)
	(footprint ""
		(layer "F.Cu")
		(at 189.849506 -164.457888 -90)
		(property "Reference" "C541"
			(at 1.80086 -1.553464 90)
			(unlocked yes)
			(layer "F.SilkS")
			(effects
				(font
					(size 0.7874 0.5842)
					(thickness 0.1524)
				)
				(justify left)
			)
		)
		(property "Value" ""
			(at 0 0 270)
			(layer "F.Fab")
			(effects
				(font
					(size 1.27 1.27)
				)
			)
		)
		(duplicate_pad_numbers_are_jumpers no)
		(fp_line
			(start -2.2098 0.9398)
			(end -2.2098 -0.9398)
			(stroke
				(width 0.1524)
				(type default)
			)
			(layer "F.SilkS")
		)
		(fp_line
			(start 2.2098 0.9398)
			(end -2.2098 0.9398)
			(stroke
				(width 0.1524)
				(type default)
			)
			(layer "F.SilkS")
		)
		(fp_line
			(start -2.2098 -0.9398)
			(end 2.2098 -0.9398)
			(stroke
				(width 0.1524)
				(type default)
			)
			(layer "F.SilkS")
		)
		(fp_line
			(start 0 -0.9398)
			(end 0 0.9398)
			(stroke
				(width 0.1524)
				(type default)
			)
			(layer "F.SilkS")
		)
		(fp_line
			(start 2.2098 -0.9398)
			(end 2.2098 0.9398)
			(stroke
				(width 0.1524)
				(type default)
			)
			(layer "F.SilkS")
		)
		(fp_poly
			(pts
				(xy -1.6764 0.889) (xy -1.6764 0.7874) (xy -2.0574 0.7874) (xy -2.0574 -0.7874) (xy -1.6764 -0.7874)
				(xy -1.6764 -0.889) (xy -1.6764 -0.9398) (xy 1.6764 -0.9398) (xy 1.6764 -0.889) (xy 1.6764 -0.7874)
				(xy 2.0574 -0.7874) (xy 2.0574 0.7874) (xy 1.6764 0.7874) (xy 1.6764 0.889) (xy 1.6764 0.9398) (xy -1.6764 0.9398)
			)
			(stroke
				(width 0)
				(type default)
			)
			(fill no)
			(layer "F.CrtYd")
		)
		(pad "1" smd rect
			(at 1.4732 0 270)
			(size 1.1684 1.5748)
			(layers "F.Cu" "F.Mask" "F.Paste")
			(net "N54134271")
		)
		(pad "2" smd rect
			(at -1.4732 0 270)
			(size 1.1684 1.5748)
			(layers "F.Cu" "F.Mask" "F.Paste")
			(net "GND")
		)
	)
)
